(kicad_pcb
	(version 20260206)
	(generator "pcbnew")
	(generator_version "10.0")
	(general
		(thickness 1.6)
		(legacy_teardrops no)
	)
	(paper "A4")
	(title_block
		(title "12092022_DA0F0TFB6D0_F0T_FAN_BOARD_MP5048_D_brd_v02_OCP.brd")
		(comment 1 "Grand Teton / footprints 862-868 of 924")
	)
	(layers
		(0 "F.Cu" signal "TOP")
		(4 "In1.Cu" signal "GND")
		(6 "In2.Cu" signal "IN1")
		(8 "In3.Cu" signal "IN2")
		(10 "In4.Cu" signal "GND1")
		(2 "B.Cu" signal "BOTTOM")
		(9 "F.Adhes" user "F.Adhesive")
		(11 "B.Adhes" user "B.Adhesive")
		(13 "F.Paste" user "Package Geometry/Pastemask Top")
		(15 "B.Paste" user "Package Geometry/Pastemask Bottom")
		(5 "F.SilkS" user "Ref Des/Silkscreen Top")
		(7 "B.SilkS" user "Ref Des/Silkscreen Bottom")
		(1 "F.Mask" user "Board Geometry/Soldermask Top")
		(3 "B.Mask" user "Board Geometry/Soldermask Bottom")
		(17 "Dwgs.User" user "User.Drawings")
		(19 "Cmts.User" user "User.Comments")
		(21 "Eco1.User" user "User.Eco1")
		(23 "Eco2.User" user "User.Eco2")
		(25 "Edge.Cuts" user "Board Geometry/Outline")
		(27 "Margin" user)
		(31 "F.CrtYd" user "Package Geometry/Place Bound Top")
		(29 "B.CrtYd" user "Package Geometry/Place Bound Bottom")
		(35 "F.Fab" user "Ref Des/Assembly Top")
		(33 "B.Fab" user "Ref Des/Assembly Bottom")
	)
	(footprint ""
		(layer "B.Cu")
		(at 39.365428 -67.494912 180)
		(property "Reference" "U74"
			(at -0.666242 1.693418 0)
			(unlocked yes)
			(layer "B.SilkS")
			(effects
				(font
					(size 0.7874 0.5842)
					(thickness 0.1524)
				)
				(justify mirror)
			)
		)
		(property "Value" ""
			(at 0 0 0)
			(layer "B.Fab")
			(effects
				(font
					(size 1.27 1.27)
				)
				(justify mirror)
			)
		)
		(duplicate_pad_numbers_are_jumpers no)
		(fp_line
			(start 1.7018 1.1176)
			(end 1.7018 -1.1176)
			(stroke
				(width 0.1524)
				(type default)
			)
			(layer "B.SilkS")
		)
		(fp_line
			(start 0.254 -1.1176)
			(end 1.7018 -1.1176)
			(stroke
				(width 0.1524)
				(type default)
			)
			(layer "B.SilkS")
		)
		(fp_line
			(start 0 -0.7112)
			(end 0.254 -1.1176)
			(stroke
				(width 0.1524)
				(type default)
			)
			(layer "B.SilkS")
		)
		(fp_line
			(start -0.254 -1.1176)
			(end 0 -0.7112)
			(stroke
				(width 0.1524)
				(type default)
			)
			(layer "B.SilkS")
		)
		(fp_line
			(start -1.7018 1.1176)
			(end 1.7018 1.1176)
			(stroke
				(width 0.1524)
				(type default)
			)
			(layer "B.SilkS")
		)
		(fp_line
			(start -1.7018 -1.1176)
			(end -0.254 -1.1176)
			(stroke
				(width 0.1524)
				(type default)
			)
			(layer "B.SilkS")
		)
		(fp_line
			(start -1.7018 -1.1176)
			(end -1.7018 1.1176)
			(stroke
				(width 0.1524)
				(type default)
			)
			(layer "B.SilkS")
		)
		(fp_poly
			(pts
				(xy 1.8161 -0.675386) (xy 2.4003 -0.446786) (xy 2.4003 -0.878586)
			)
			(stroke
				(width 0)
				(type default)
			)
			(fill yes)
			(layer "B.SilkS")
		)
		(fp_line
			(start 1.5494 1.1176)
			(end 1.5494 -1.1176)
			(stroke
				(width 0.1)
				(type default)
			)
			(layer "B.Fab")
		)
		(fp_line
			(start 0.254 -1.1176)
			(end 1.5494 -1.1176)
			(stroke
				(width 0.1)
				(type default)
			)
			(layer "B.Fab")
		)
		(fp_line
			(start -0.254 -1.1176)
			(end 0.254 -1.1176)
			(stroke
				(width 0.1)
				(type default)
			)
			(layer "B.Fab")
		)
		(fp_line
			(start -1.5494 1.1176)
			(end 1.5494 1.1176)
			(stroke
				(width 0.1)
				(type default)
			)
			(layer "B.Fab")
		)
		(fp_line
			(start -1.5494 -1.1176)
			(end -0.254 -1.1176)
			(stroke
				(width 0.1)
				(type default)
			)
			(layer "B.Fab")
		)
		(fp_line
			(start -1.5494 -1.1176)
			(end -1.5494 1.1176)
			(stroke
				(width 0.1)
				(type default)
			)
			(layer "B.Fab")
		)
		(fp_poly
			(pts
				(xy 1.8161 -0.675386) (xy 2.4003 -0.446786) (xy 2.4003 -0.878586)
			)
			(stroke
				(width 0)
				(type default)
			)
			(fill yes)
			(layer "B.Fab")
		)
		(pad "1" smd rect
			(at 0.962406 -0.649986 90)
			(size 0.3302 1.1684)
			(layers "B.Cu" "B.Mask" "B.Paste")
			(net "FAN_3_PRESENT_R")
		)
		(pad "2" smd rect
			(at 0.962406 0 90)
			(size 0.3302 1.1684)
			(layers "B.Cu" "B.Mask" "B.Paste")
			(net "P52V_FAN_3_BUFF_EN_R")
		)
		(pad "3" smd rect
			(at 0.962406 0.649986 90)
			(size 0.3302 1.1684)
			(layers "B.Cu" "B.Mask" "B.Paste")
			(net "GND")
		)
		(pad "4" smd rect
			(at -0.962406 0.649986 90)
			(size 0.3302 1.1684)
			(layers "B.Cu" "B.Mask" "B.Paste")
			(net "P52V_FAN_3_EN")
		)
		(pad "5" smd rect
			(at -0.962406 -0.649986 90)
			(size 0.3302 1.1684)
			(layers "B.Cu" "B.Mask" "B.Paste")
			(net "P3V3_AUX")
		)
	)
	(footprint ""
		(layer "B.Cu")
		(at 39.73068 -73.962768 90)
		(property "Reference" "PC32"
			(at 0 0 90)
			(layer "B.SilkS")
			(hide yes)
			(effects
				(font
					(size 1.27 1.27)
				)
				(justify mirror)
			)
		)
		(property "Value" ""
			(at 0 0 90)
			(layer "B.Fab")
			(effects
				(font
					(size 1.27 1.27)
				)
				(justify mirror)
			)
		)
		(duplicate_pad_numbers_are_jumpers no)
		(fp_line
			(start 0.7874 -0.4064)
			(end -0.7874 -0.4064)
			(stroke
				(width 0.1524)
				(type default)
			)
			(layer "B.SilkS")
		)
		(fp_line
			(start -0.7874 -0.4064)
			(end -0.7874 0.4064)
			(stroke
				(width 0.1524)
				(type default)
			)
			(layer "B.SilkS")
		)
		(fp_line
			(start 0.7874 0.4064)
			(end 0.7874 -0.4064)
			(stroke
				(width 0.1524)
				(type default)
			)
			(layer "B.SilkS")
		)
		(fp_line
			(start -0.7874 0.4064)
			(end 0.7874 0.4064)
			(stroke
				(width 0.1524)
				(type default)
			)
			(layer "B.SilkS")
		)
		(fp_line
			(start 0.67945 -0.305054)
			(end 0.12065 -0.305054)
			(stroke
				(width 0.1)
				(type default)
			)
			(layer "B.Fab")
		)
		(fp_line
			(start 0.12065 -0.305054)
			(end 0.12065 -0.2794)
			(stroke
				(width 0.1)
				(type default)
			)
			(layer "B.Fab")
		)
		(fp_line
			(start -0.12065 -0.3048)
			(end -0.67945 -0.3048)
			(stroke
				(width 0.1)
				(type default)
			)
			(layer "B.Fab")
		)
		(fp_line
			(start -0.67945 -0.3048)
			(end -0.67945 0.3048)
			(stroke
				(width 0.1)
				(type default)
			)
			(layer "B.Fab")
		)
		(fp_line
			(start 0.12065 -0.2794)
			(end -0.12065 -0.2794)
			(stroke
				(width 0.1)
				(type default)
			)
			(layer "B.Fab")
		)
		(fp_line
			(start -0.12065 -0.2794)
			(end -0.12065 -0.3048)
			(stroke
				(width 0.1)
				(type default)
			)
			(layer "B.Fab")
		)
		(fp_line
			(start 0.12065 0.2794)
			(end 0.12065 0.3048)
			(stroke
				(width 0.1)
				(type default)
			)
			(layer "B.Fab")
		)
		(fp_line
			(start -0.120396 0.2794)
			(end 0.12065 0.2794)
			(stroke
				(width 0.1)
				(type default)
			)
			(layer "B.Fab")
		)
		(fp_line
			(start 0.67945 0.3048)
			(end 0.67945 -0.305054)
			(stroke
				(width 0.1)
				(type default)
			)
			(layer "B.Fab")
		)
		(fp_line
			(start 0.12065 0.3048)
			(end 0.67945 0.3048)
			(stroke
				(width 0.1)
				(type default)
			)
			(layer "B.Fab")
		)
		(fp_line
			(start -0.120396 0.3048)
			(end -0.120396 0.2794)
			(stroke
				(width 0.1)
				(type default)
			)
			(layer "B.Fab")
		)
		(fp_line
			(start -0.67945 0.3048)
			(end -0.120396 0.3048)
			(stroke
				(width 0.1)
				(type default)
			)
			(layer "B.Fab")
		)
		(pad "1" smd circle
			(at 0.40005 0 270)
			(size 0 0)
			(layers "B.Cu" "B.Mask" "B.Paste")
			(net "FAN_2_P5V")
		)
		(pad "2" smd circle
			(at -0.40005 0 270)
			(size 0 0)
			(layers "B.Cu" "B.Mask" "B.Paste")
			(net "GND")
		)
	)
	(footprint ""
		(layer "B.Cu")
		(at 5.550154 -53.062124)
		(property "Reference" "PC37"
			(at 0 0 0)
			(layer "B.SilkS")
			(hide yes)
			(effects
				(font
					(size 1.27 1.27)
				)
				(justify mirror)
			)
		)
		(property "Value" ""
			(at 0 0 0)
			(layer "B.Fab")
			(effects
				(font
					(size 1.27 1.27)
				)
				(justify mirror)
			)
		)
		(duplicate_pad_numbers_are_jumpers no)
		(fp_line
			(start -1.524 -0.762)
			(end -1.524 0.762)
			(stroke
				(width 0.1524)
				(type default)
			)
			(layer "B.SilkS")
		)
		(fp_line
			(start -1.524 0.762)
			(end 1.524 0.762)
			(stroke
				(width 0.1524)
				(type default)
			)
			(layer "B.SilkS")
		)
		(fp_line
			(start 1.524 -0.762)
			(end -1.524 -0.762)
			(stroke
				(width 0.1524)
				(type default)
			)
			(layer "B.SilkS")
		)
		(fp_line
			(start 1.524 0.762)
			(end 1.524 -0.762)
			(stroke
				(width 0.1524)
				(type default)
			)
			(layer "B.SilkS")
		)
		(fp_line
			(start -1.1049 -0.724916)
			(end 1.1049 -0.724916)
			(stroke
				(width 0.1)
				(type default)
			)
			(layer "B.Fab")
		)
		(fp_line
			(start -1.1049 0.724916)
			(end -1.1049 -0.724916)
			(stroke
				(width 0.1)
				(type default)
			)
			(layer "B.Fab")
		)
		(fp_line
			(start 1.1049 -0.724916)
			(end 1.1049 0.724916)
			(stroke
				(width 0.1)
				(type default)
			)
			(layer "B.Fab")
		)
		(fp_line
			(start 1.1049 0.724916)
			(end -1.1049 0.724916)
			(stroke
				(width 0.1)
				(type default)
			)
			(layer "B.Fab")
		)
		(pad "1" smd rect
			(at 0.889 0)
			(size 1.016 1.27)
			(layers "B.Cu" "B.Mask" "B.Paste")
			(net "P52V_FAN_4")
		)
		(pad "2" smd rect
			(at -0.889 0)
			(size 1.016 1.27)
			(layers "B.Cu" "B.Mask" "B.Paste")
			(net "GND")
		)
	)
	(footprint ""
		(layer "B.Cu")
		(at 42.164 -250.23699 -90)
		(property "Reference" "PC2119"
			(at 0 0 90)
			(layer "B.SilkS")
			(hide yes)
			(effects
				(font
					(size 1.27 1.27)
				)
				(justify mirror)
			)
		)
		(property "Value" ""
			(at 0 0 90)
			(layer "B.Fab")
			(effects
				(font
					(size 1.27 1.27)
				)
				(justify mirror)
			)
		)
		(duplicate_pad_numbers_are_jumpers no)
		(fp_line
			(start -0.7874 0.4064)
			(end 0.7874 0.4064)
			(stroke
				(width 0.1524)
				(type default)
			)
			(layer "B.SilkS")
		)
		(fp_line
			(start 0.7874 0.4064)
			(end 0.7874 -0.4064)
			(stroke
				(width 0.1524)
				(type default)
			)
			(layer "B.SilkS")
		)
		(fp_line
			(start -0.7874 -0.4064)
			(end -0.7874 0.4064)
			(stroke
				(width 0.1524)
				(type default)
			)
			(layer "B.SilkS")
		)
		(fp_line
			(start 0.7874 -0.4064)
			(end -0.7874 -0.4064)
			(stroke
				(width 0.1524)
				(type default)
			)
			(layer "B.SilkS")
		)
		(fp_line
			(start -0.67945 0.3048)
			(end -0.120396 0.3048)
			(stroke
				(width 0.1)
				(type default)
			)
			(layer "B.Fab")
		)
		(fp_line
			(start -0.120396 0.3048)
			(end -0.120396 0.2794)
			(stroke
				(width 0.1)
				(type default)
			)
			(layer "B.Fab")
		)
		(fp_line
			(start 0.12065 0.3048)
			(end 0.67945 0.3048)
			(stroke
				(width 0.1)
				(type default)
			)
			(layer "B.Fab")
		)
		(fp_line
			(start 0.67945 0.3048)
			(end 0.67945 -0.305054)
			(stroke
				(width 0.1)
				(type default)
			)
			(layer "B.Fab")
		)
		(fp_line
			(start -0.120396 0.2794)
			(end 0.12065 0.2794)
			(stroke
				(width 0.1)
				(type default)
			)
			(layer "B.Fab")
		)
		(fp_line
			(start 0.12065 0.2794)
			(end 0.12065 0.3048)
			(stroke
				(width 0.1)
				(type default)
			)
			(layer "B.Fab")
		)
		(fp_line
			(start -0.12065 -0.2794)
			(end -0.12065 -0.3048)
			(stroke
				(width 0.1)
				(type default)
			)
			(layer "B.Fab")
		)
		(fp_line
			(start 0.12065 -0.2794)
			(end -0.12065 -0.2794)
			(stroke
				(width 0.1)
				(type default)
			)
			(layer "B.Fab")
		)
		(fp_line
			(start -0.67945 -0.3048)
			(end -0.67945 0.3048)
			(stroke
				(width 0.1)
				(type default)
			)
			(layer "B.Fab")
		)
		(fp_line
			(start -0.12065 -0.3048)
			(end -0.67945 -0.3048)
			(stroke
				(width 0.1)
				(type default)
			)
			(layer "B.Fab")
		)
		(fp_line
			(start 0.12065 -0.305054)
			(end 0.12065 -0.2794)
			(stroke
				(width 0.1)
				(type default)
			)
			(layer "B.Fab")
		)
		(fp_line
			(start 0.67945 -0.305054)
			(end 0.12065 -0.305054)
			(stroke
				(width 0.1)
				(type default)
			)
			(layer "B.Fab")
		)
		(pad "1" smd circle
			(at 0.40005 0 90)
			(size 0 0)
			(layers "B.Cu" "B.Mask" "B.Paste")
			(net "FAN_1_TEMP")
		)
		(pad "2" smd circle
			(at -0.40005 0 90)
			(size 0 0)
			(layers "B.Cu" "B.Mask" "B.Paste")
			(net "GND")
		)
	)
	(footprint ""
		(layer "B.Cu")
		(at 14.097 -73.971912 -90)
		(property "Reference" "PC3123"
			(at 0 0 90)
			(layer "B.SilkS")
			(hide yes)
			(effects
				(font
					(size 1.27 1.27)
				)
				(justify mirror)
			)
		)
		(property "Value" ""
			(at 0 0 90)
			(layer "B.Fab")
			(effects
				(font
					(size 1.27 1.27)
				)
				(justify mirror)
			)
		)
		(duplicate_pad_numbers_are_jumpers no)
		(fp_line
			(start -0.7874 0.4064)
			(end 0.7874 0.4064)
			(stroke
				(width 0.1524)
				(type default)
			)
			(layer "B.SilkS")
		)
		(fp_line
			(start 0.7874 0.4064)
			(end 0.7874 -0.4064)
			(stroke
				(width 0.1524)
				(type default)
			)
			(layer "B.SilkS")
		)
		(fp_line
			(start -0.7874 -0.4064)
			(end -0.7874 0.4064)
			(stroke
				(width 0.1524)
				(type default)
			)
			(layer "B.SilkS")
		)
		(fp_line
			(start 0.7874 -0.4064)
			(end -0.7874 -0.4064)
			(stroke
				(width 0.1524)
				(type default)
			)
			(layer "B.SilkS")
		)
		(fp_line
			(start -0.67945 0.3048)
			(end -0.120396 0.3048)
			(stroke
				(width 0.1)
				(type default)
			)
			(layer "B.Fab")
		)
		(fp_line
			(start -0.120396 0.3048)
			(end -0.120396 0.2794)
			(stroke
				(width 0.1)
				(type default)
			)
			(layer "B.Fab")
		)
		(fp_line
			(start 0.12065 0.3048)
			(end 0.67945 0.3048)
			(stroke
				(width 0.1)
				(type default)
			)
			(layer "B.Fab")
		)
		(fp_line
			(start 0.67945 0.3048)
			(end 0.67945 -0.305054)
			(stroke
				(width 0.1)
				(type default)
			)
			(layer "B.Fab")
		)
		(fp_line
			(start -0.120396 0.2794)
			(end 0.12065 0.2794)
			(stroke
				(width 0.1)
				(type default)
			)
			(layer "B.Fab")
		)
		(fp_line
			(start 0.12065 0.2794)
			(end 0.12065 0.3048)
			(stroke
				(width 0.1)
				(type default)
			)
			(layer "B.Fab")
		)
		(fp_line
			(start -0.12065 -0.2794)
			(end -0.12065 -0.3048)
			(stroke
				(width 0.1)
				(type default)
			)
			(layer "B.Fab")
		)
		(fp_line
			(start 0.12065 -0.2794)
			(end -0.12065 -0.2794)
			(stroke
				(width 0.1)
				(type default)
			)
			(layer "B.Fab")
		)
		(fp_line
			(start -0.67945 -0.3048)
			(end -0.67945 0.3048)
			(stroke
				(width 0.1)
				(type default)
			)
			(layer "B.Fab")
		)
		(fp_line
			(start -0.12065 -0.3048)
			(end -0.67945 -0.3048)
			(stroke
				(width 0.1)
				(type default)
			)
			(layer "B.Fab")
		)
		(fp_line
			(start 0.12065 -0.305054)
			(end 0.12065 -0.2794)
			(stroke
				(width 0.1)
				(type default)
			)
			(layer "B.Fab")
		)
		(fp_line
			(start 0.67945 -0.305054)
			(end 0.12065 -0.305054)
			(stroke
				(width 0.1)
				(type default)
			)
			(layer "B.Fab")
		)
		(pad "1" smd circle
			(at 0.40005 0 90)
			(size 0 0)
			(layers "B.Cu" "B.Mask" "B.Paste")
			(net "GND")
		)
		(pad "2" smd circle
			(at -0.40005 0 90)
			(size 0 0)
			(layers "B.Cu" "B.Mask" "B.Paste")
			(net "FAN_5_CLREF")
		)
	)
	(footprint ""
		(layer "B.Cu")
		(at 44.667932 -255.778 -90)
		(property "Reference" "U394"
			(at 1.651 -2.930398 270)
			(unlocked yes)
			(layer "B.SilkS")
			(effects
				(font
					(size 0.7874 0.5842)
					(thickness 0.1524)
				)
				(justify left mirror)
			)
		)
		(property "Value" ""
			(at 0 0 90)
			(layer "B.Fab")
			(effects
				(font
					(size 1.27 1.27)
				)
				(justify mirror)
			)
		)
		(duplicate_pad_numbers_are_jumpers no)
		(fp_line
			(start -1.3462 1.1938)
			(end -1.3462 -1.1938)
			(stroke
				(width 0.1524)
				(type default)
			)
			(layer "B.SilkS")
		)
		(fp_line
			(start 1.3462 1.1938)
			(end -1.3462 1.1938)
			(stroke
				(width 0.1524)
				(type default)
			)
			(layer "B.SilkS")
		)
		(fp_line
			(start -1.3462 -1.1938)
			(end 1.3462 -1.1938)
			(stroke
				(width 0.1524)
				(type default)
			)
			(layer "B.SilkS")
		)
		(fp_line
			(start 1.3462 -1.1938)
			(end 1.3462 1.1684)
			(stroke
				(width 0.1524)
				(type default)
			)
			(layer "B.SilkS")
		)
		(fp_poly
			(pts
				(xy 1.447038 -0.760476) (xy 2.052066 -0.457962) (xy 2.052066 -1.06299)
			)
			(stroke
				(width 0)
				(type default)
			)
			(fill yes)
			(layer "B.SilkS")
		)
		(fp_line
			(start -0.674878 1.124966)
			(end -0.674878 -1.124966)
			(stroke
				(width 0.1)
				(type default)
			)
			(layer "B.Fab")
		)
		(fp_line
			(start 0.674878 1.124966)
			(end -0.674878 1.124966)
			(stroke
				(width 0.1)
				(type default)
			)
			(layer "B.Fab")
		)
		(fp_line
			(start -0.674878 -1.124966)
			(end 0.674878 -1.124966)
			(stroke
				(width 0.1)
				(type default)
			)
			(layer "B.Fab")
		)
		(fp_line
			(start 0.674878 -1.124966)
			(end 0.674878 1.124966)
			(stroke
				(width 0.1)
				(type default)
			)
			(layer "B.Fab")
		)
		(fp_poly
			(pts
				(xy 1.447038 -0.760476) (xy 2.052066 -0.457962) (xy 2.052066 -1.06299)
			)
			(stroke
				(width 0)
				(type default)
			)
			(fill yes)
			(layer "B.Fab")
		)
		(pad "1" smd rect
			(at 0.899922 -0.750062 90)
			(size 0.6096 0.6096)
			(layers "B.Cu" "B.Mask" "B.Paste")
			(net "NC_U394_P1")
		)
		(pad "2" smd rect
			(at 0.899922 0)
			(size 0.4064 0.6096)
			(layers "B.Cu" "B.Mask" "B.Paste")
			(net "FAN_0_PRSNT_BUF_N")
		)
		(pad "3" smd rect
			(at 0.899922 0.750062 90)
			(size 0.6096 0.6096)
			(layers "B.Cu" "B.Mask" "B.Paste")
			(net "GND")
		)
		(pad "4" smd rect
			(at -0.899922 0.750062 90)
			(size 0.6096 0.6096)
			(layers "B.Cu" "B.Mask" "B.Paste")
			(net "FAN_0_PRESENT")
		)
		(pad "5" smd rect
			(at -0.899922 -0.750062 90)
			(size 0.6096 0.6096)
			(layers "B.Cu" "B.Mask" "B.Paste")
			(net "P3V3_AUX")
		)
	)
	(footprint ""
		(layer "B.Cu")
		(at 16.002 -314.198)
		(property "Reference" ""
			(at 0 0 0)
			(layer "B.SilkS")
			(hide yes)
			(effects
				(font
					(size 1.27 1.27)
				)
				(justify mirror)
			)
		)
		(property "Value" ""
			(at 0 0 0)
			(layer "B.Fab")
			(effects
				(font
					(size 1.27 1.27)
				)
				(justify mirror)
			)
		)
		(duplicate_pad_numbers_are_jumpers no)
		(pad "1" smd circle
			(at 0 0 180)
			(size 0.9906 0.9906)
			(layers "B.Cu" "B.Mask" "B.Paste")
			(net "Net_123")
		)
		(zone
			(layer "B.Cu")
			(hatch none 0.5)
			(connect_pads
				(clearance 0)
			)
			(min_thickness 0.25)
			(keepout
				(tracks not_allowed)
				(vias allowed)
				(pads allowed)
				(copperpour not_allowed)
				(footprints allowed)
			)
			(placement
				(enabled no)
				(sheetname "")
			)
			(fill
				(thermal_gap 0.5)
				(thermal_bridge_width 0.5)
				(island_removal_mode 0)
			)
			(polygon
				(pts
					(arc
						(start 17.6276 -314.198)
						(mid 14.3764 -314.198)
						(end 17.6276 -314.198)
					)
				)
			)
		)
	)
)
